# BASEBOARD_FAB2 (Tioga Pass) — schematic netlist excerpt (pin names and nets, part order shuffled) for the footprints in the layout excerpt that follows; sources: Cadence DE-HDL packaged netlist, KiCad conversion of Wiwynn_Tioga_Pass_MB.brd

C1E22  CAP_A  0.1UF 16V 10% X7R  pkg 0402V  page 161 : A = P3V3_STBY ; B = GND
DS9A5  LED  IC  pkg A1LF  page 119 : A = FM_PWR_LED_A ; C = FM_PWR_LED_K

(kicad_pcb
	(version 20260206)
	(generator "pcbnew")
	(generator_version "10.0")
	(general
		(thickness 1.6)
		(legacy_teardrops no)
	)
	(paper "A4")
	(title_block
		(title "Wiwynn_Tioga_Pass_MB.brd")
		(comment 1 "Tioga Pass / footprints 795-796 of 4770")
	)
	(layers
		(0 "F.Cu" signal "TOP")
		(4 "In1.Cu" signal "L2GND")
		(6 "In2.Cu" signal "L3")
		(8 "In3.Cu" signal "L4GND")
		(10 "In4.Cu" signal "L5")
		(12 "In5.Cu" signal "L6GND")
		(14 "In6.Cu" signal "L7VCC")
		(16 "In7.Cu" signal "L8VCC")
		(18 "In8.Cu" signal "L9GND")
		(20 "In9.Cu" signal "L10")
		(22 "In10.Cu" signal "L11GND")
		(24 "In11.Cu" signal "L12")
		(26 "In12.Cu" signal "L13GND")
		(2 "B.Cu" signal "BOTTOM")
		(9 "F.Adhes" user "F.Adhesive")
		(11 "B.Adhes" user "B.Adhesive")
		(13 "F.Paste" user "Package Geometry/Pastemask Top")
		(15 "B.Paste" user "Package Geometry/Pastemask Bottom")
		(5 "F.SilkS" user "Ref Des/Silkscreen Top")
		(7 "B.SilkS" user "Ref Des/Silkscreen Bottom")
		(1 "F.Mask" user "Board Geometry/Soldermask Top")
		(3 "B.Mask" user "Board Geometry/Soldermask Bottom")
		(17 "Dwgs.User" user "User.Drawings")
		(19 "Cmts.User" user "User.Comments")
		(21 "Eco1.User" user "User.Eco1")
		(23 "Eco2.User" user "User.Eco2")
		(25 "Edge.Cuts" user "Board Geometry/Outline")
		(27 "Margin" user)
		(31 "F.CrtYd" user "Package Geometry/Place Bound Top")
		(29 "B.CrtYd" user "Package Geometry/Place Bound Bottom")
		(35 "F.Fab" user "Ref Des/Assembly Top")
		(33 "B.Fab" user "Ref Des/Assembly Bottom")
	)
	(footprint ""
		(layer "F.Cu")
		(at 480.22764 -137.328402 -90)
		(property "Reference" "DS9A5"
			(at -0.9017 3.57505 90)
			(unlocked yes)
			(layer "F.SilkS")
			(effects
				(font
					(size 0.7874 0.5842)
					(thickness 0.1524)
				)
			)
		)
		(property "Value" ""
			(at 0 0 270)
			(layer "F.Fab")
			(effects
				(font
					(size 1.27 1.27)
				)
			)
		)
		(duplicate_pad_numbers_are_jumpers no)
		(fp_line
			(start -0.1016 5.61213)
			(end -0.1016 4.488688)
			(stroke
				(width 0.1524)
				(type default)
			)
			(layer "F.SilkS")
		)
		(fp_line
			(start -0.582422 4.488688)
			(end 0.379222 4.488688)
			(stroke
				(width 0.1524)
				(type default)
			)
			(layer "F.SilkS")
		)
		(fp_line
			(start -0.1016 4.488688)
			(end -0.582422 3.655822)
			(stroke
				(width 0.1524)
				(type default)
			)
			(layer "F.SilkS")
		)
		(fp_line
			(start -0.582422 3.655822)
			(end -0.1016 3.655822)
			(stroke
				(width 0.1524)
				(type default)
			)
			(layer "F.SilkS")
		)
		(fp_line
			(start -0.1016 3.655822)
			(end 0.379222 3.655822)
			(stroke
				(width 0.1524)
				(type default)
			)
			(layer "F.SilkS")
		)
		(fp_line
			(start 0.379222 3.655822)
			(end -0.1016 4.488688)
			(stroke
				(width 0.1524)
				(type default)
			)
			(layer "F.SilkS")
		)
		(fp_line
			(start -0.1016 2.744216)
			(end -0.1016 3.655822)
			(stroke
				(width 0.1524)
				(type default)
			)
			(layer "F.SilkS")
		)
		(fp_poly
			(pts
				(xy 0.6223 2.032) (xy -0.6223 2.032) (xy -0.6223 0.0254) (xy 0.6223 0.0254)
			)
			(stroke
				(width 0)
				(type default)
			)
			(fill no)
			(layer "F.CrtYd")
		)
		(fp_line
			(start -0.582422 4.488688)
			(end 0.379222 4.488688)
			(stroke
				(width 0.1)
				(type default)
			)
			(layer "F.Fab")
		)
		(fp_line
			(start -0.1016 4.488688)
			(end -0.1016 5.61213)
			(stroke
				(width 0.1)
				(type default)
			)
			(layer "F.Fab")
		)
		(fp_line
			(start -0.1016 4.488688)
			(end -0.582422 3.655822)
			(stroke
				(width 0.1)
				(type default)
			)
			(layer "F.Fab")
		)
		(fp_line
			(start -0.582422 3.655822)
			(end 0.379222 3.655822)
			(stroke
				(width 0.1)
				(type default)
			)
			(layer "F.Fab")
		)
		(fp_line
			(start -0.1016 3.655822)
			(end -0.1016 2.744216)
			(stroke
				(width 0.1)
				(type default)
			)
			(layer "F.Fab")
		)
		(fp_line
			(start 0.379222 3.655822)
			(end -0.1016 4.488688)
			(stroke
				(width 0.1)
				(type default)
			)
			(layer "F.Fab")
		)
		(fp_line
			(start -0.6223 2.032)
			(end -0.6223 0.0254)
			(stroke
				(width 0.1)
				(type default)
			)
			(layer "F.Fab")
		)
		(fp_line
			(start 0.6223 2.032)
			(end -0.6223 2.032)
			(stroke
				(width 0.1)
				(type default)
			)
			(layer "F.Fab")
		)
		(fp_line
			(start -0.6223 0.0254)
			(end 0.6223 0.0254)
			(stroke
				(width 0.1)
				(type default)
			)
			(layer "F.Fab")
		)
		(fp_line
			(start 0.6223 0.0254)
			(end 0.6223 2.032)
			(stroke
				(width 0.1)
				(type default)
			)
			(layer "F.Fab")
		)
		(pad "1" smd rect
			(at 0 0 270)
			(size 1.27 1.27)
			(layers "F.Cu" "F.Mask" "F.Paste")
			(net "FM_PWR_LED_A")
		)
		(pad "2" smd rect
			(at 0 2.032 270)
			(size 1.27 1.27)
			(layers "F.Cu" "F.Mask" "F.Paste")
			(net "FM_PWR_LED_K")
		)
		(zone
			(layer "F.Cu")
			(hatch none 0.5)
			(connect_pads
				(clearance 0)
			)
			(min_thickness 0.25)
			(keepout
				(tracks not_allowed)
				(vias allowed)
				(pads allowed)
				(copperpour not_allowed)
				(footprints allowed)
			)
			(placement
				(enabled no)
				(sheetname "")
			)
			(fill
				(thermal_gap 0.5)
				(thermal_bridge_width 0.5)
				(island_removal_mode 0)
			)
			(polygon
				(pts
					(xy 478.83064 -137.963402) (xy 478.83064 -136.693402) (xy 479.59264 -136.693402) (xy 479.59264 -137.963402)
				)
			)
		)
		(zone
			(layer "F.Cu")
			(hatch none 0.5)
			(connect_pads
				(clearance 0)
			)
			(min_thickness 0.25)
			(keepout
				(tracks allowed)
				(vias not_allowed)
				(pads allowed)
				(copperpour not_allowed)
				(footprints allowed)
			)
			(placement
				(enabled no)
				(sheetname "")
			)
			(fill
				(thermal_gap 0.5)
				(thermal_bridge_width 0.5)
				(island_removal_mode 0)
			)
			(polygon
				(pts
					(xy 478.83064 -137.963402) (xy 478.83064 -136.693402) (xy 479.59264 -136.693402) (xy 479.59264 -137.963402)
				)
			)
		)
	)
	(footprint ""
		(layer "F.Cu")
		(at 17.0434 -41.5036 -90)
		(property "Reference" "C1E22"
			(at 0 0 270)
			(layer "F.SilkS")
			(hide yes)
			(effects
				(font
					(size 1.27 1.27)
				)
			)
		)
		(property "Value" ""
			(at 0 0 270)
			(layer "F.Fab")
			(effects
				(font
					(size 1.27 1.27)
				)
			)
		)
		(duplicate_pad_numbers_are_jumpers no)
		(fp_poly
			(pts
				(xy 0.3048 -0.1016) (xy 0.3048 0.9906) (xy -0.3048 0.9906) (xy -0.3048 -0.1016)
			)
			(stroke
				(width 0)
				(type default)
			)
			(fill no)
			(layer "F.CrtYd")
		)
		(fp_line
			(start -0.3048 0.9906)
			(end 0.3048 0.9906)
			(stroke
				(width 0.1)
				(type default)
			)
			(layer "F.Fab")
		)
		(fp_line
			(start 0.3048 0.9906)
			(end 0.3048 -0.1016)
			(stroke
				(width 0.1)
				(type default)
			)
			(layer "F.Fab")
		)
		(fp_line
			(start -0.3048 -0.1016)
			(end -0.3048 0.9906)
			(stroke
				(width 0.1)
				(type default)
			)
			(layer "F.Fab")
		)
		(fp_line
			(start 0.3048 -0.1016)
			(end -0.3048 -0.1016)
			(stroke
				(width 0.1)
				(type default)
			)
			(layer "F.Fab")
		)
		(pad "1" smd rect
			(at 0 0 270)
			(size 0.508 0.508)
			(layers "F.Cu" "F.Mask" "F.Paste")
			(net "P3V3_STBY")
		)
		(pad "2" smd rect
			(at 0 0.889 270)
			(size 0.508 0.508)
			(layers "F.Cu" "F.Mask" "F.Paste")
			(net "GND")
		)
		(zone
			(layer "F.Cu")
			(hatch none 0.5)
			(connect_pads
				(clearance 0)
			)
			(min_thickness 0.25)
			(keepout
				(tracks not_allowed)
				(vias allowed)
				(pads allowed)
				(copperpour not_allowed)
				(footprints allowed)
			)
			(placement
				(enabled no)
				(sheetname "")
			)
			(fill
				(thermal_gap 0.5)
				(thermal_bridge_width 0.5)
				(island_removal_mode 0)
			)
			(polygon
				(pts
					(xy 16.4084 -41.7576) (xy 16.4084 -41.2496) (xy 16.7894 -41.2496) (xy 16.7894 -41.7576)
				)
			)
		)
		(zone
			(layer "F.Cu")
			(hatch none 0.5)
			(connect_pads
				(clearance 0)
			)
			(min_thickness 0.25)
			(keepout
				(tracks allowed)
				(vias not_allowed)
				(pads allowed)
				(copperpour not_allowed)
				(footprints allowed)
			)
			(placement
				(enabled no)
				(sheetname "")
			)
			(fill
				(thermal_gap 0.5)
				(thermal_bridge_width 0.5)
				(island_removal_mode 0)
			)
			(polygon
				(pts
					(xy 16.7894 -41.7576) (xy 16.7894 -41.2496) (xy 16.4084 -41.2496) (xy 16.4084 -41.7576)
				)
			)
		)
	)
)
